(kicad_pcb
	(version 20260206)
	(generator "pcbnew")
	(generator_version "10.0")
	(general
		(thickness 1.6)
		(legacy_teardrops no)
	)
	(paper "A4")
	(title_block
		(title "01162023_DA0F0TEBIF0_F0T_Expander_BD_F_brd_V02_OCP.brd")
		(comment 1 "Grand Teton / footprints 9024-9032 of 9728")
	)
	(layers
		(0 "F.Cu" signal "TOP")
		(4 "In1.Cu" signal "GND")
		(6 "In2.Cu" signal "VCC")
		(8 "In3.Cu" signal "VCC1")
		(10 "In4.Cu" signal "GND1")
		(12 "In5.Cu" signal "IN1")
		(14 "In6.Cu" signal "GND2")
		(16 "In7.Cu" signal "IN2")
		(18 "In8.Cu" signal "GND3")
		(20 "In9.Cu" signal "IN3")
		(22 "In10.Cu" signal "GND4")
		(24 "In11.Cu" signal "IN4")
		(26 "In12.Cu" signal "GND5")
		(28 "In13.Cu" signal "IN5")
		(30 "In14.Cu" signal "GND6")
		(32 "In15.Cu" signal "IN6")
		(34 "In16.Cu" signal "GND7")
		(2 "B.Cu" signal "BOTTOM")
		(9 "F.Adhes" user "F.Adhesive")
		(11 "B.Adhes" user "B.Adhesive")
		(13 "F.Paste" user "Package Geometry/Pastemask Top")
		(15 "B.Paste" user "Package Geometry/Pastemask Bottom")
		(5 "F.SilkS" user "Ref Des/Silkscreen Top")
		(7 "B.SilkS" user "Ref Des/Silkscreen Bottom")
		(1 "F.Mask" user "Board Geometry/Soldermask Top")
		(3 "B.Mask" user "Board Geometry/Soldermask Bottom")
		(17 "Dwgs.User" user "User.Drawings")
		(19 "Cmts.User" user "User.Comments")
		(21 "Eco1.User" user "User.Eco1")
		(23 "Eco2.User" user "User.Eco2")
		(25 "Edge.Cuts" user "Board Geometry/Outline")
		(27 "Margin" user)
		(31 "F.CrtYd" user "Package Geometry/Place Bound Top")
		(29 "B.CrtYd" user "Package Geometry/Place Bound Bottom")
		(35 "F.Fab" user "Ref Des/Assembly Top")
		(33 "B.Fab" user "Ref Des/Assembly Bottom")
	)
	(footprint ""
		(layer "B.Cu")
		(at 53.949854 -301.599854 -90)
		(property "Reference" "C1222"
			(at 0 0 90)
			(layer "B.SilkS")
			(hide yes)
			(effects
				(font
					(size 1.27 1.27)
				)
				(justify mirror)
			)
		)
		(property "Value" ""
			(at 0 0 90)
			(layer "B.Fab")
			(effects
				(font
					(size 1.27 1.27)
				)
				(justify mirror)
			)
		)
		(duplicate_pad_numbers_are_jumpers no)
		(fp_line
			(start -0.299974 0.150114)
			(end 0.299974 0.150114)
			(stroke
				(width 0.1)
				(type default)
			)
			(layer "B.Fab")
		)
		(fp_line
			(start 0.299974 0.150114)
			(end 0.299974 -0.150114)
			(stroke
				(width 0.1)
				(type default)
			)
			(layer "B.Fab")
		)
		(fp_line
			(start -0.299974 -0.150114)
			(end -0.299974 0.150114)
			(stroke
				(width 0.1)
				(type default)
			)
			(layer "B.Fab")
		)
		(fp_line
			(start 0.299974 -0.150114)
			(end -0.299974 -0.150114)
			(stroke
				(width 0.1)
				(type default)
			)
			(layer "B.Fab")
		)
		(pad "1" smd rect
			(at 0.2667 0 90)
			(size 0.3048 0.381)
			(layers "B.Cu" "B.Mask" "B.Paste")
			(net "P0V8_SERDES_VDDA_PEX0")
		)
		(pad "2" smd rect
			(at -0.2667 0 90)
			(size 0.3048 0.381)
			(layers "B.Cu" "B.Mask" "B.Paste")
			(net "GND")
		)
	)
	(footprint ""
		(layer "B.Cu")
		(at 15.012416 -221.640908 90)
		(property "Reference" "R3450"
			(at 0 0 90)
			(layer "B.SilkS")
			(hide yes)
			(effects
				(font
					(size 1.27 1.27)
				)
				(justify mirror)
			)
		)
		(property "Value" ""
			(at 0 0 90)
			(layer "B.Fab")
			(effects
				(font
					(size 1.27 1.27)
				)
				(justify mirror)
			)
		)
		(duplicate_pad_numbers_are_jumpers no)
		(fp_line
			(start 0.7874 -0.4064)
			(end -0.7874 -0.4064)
			(stroke
				(width 0.1524)
				(type default)
			)
			(layer "B.SilkS")
		)
		(fp_line
			(start -0.7874 -0.4064)
			(end -0.7874 0.4064)
			(stroke
				(width 0.1524)
				(type default)
			)
			(layer "B.SilkS")
		)
		(fp_line
			(start 0.7874 0.4064)
			(end 0.7874 -0.4064)
			(stroke
				(width 0.1524)
				(type default)
			)
			(layer "B.SilkS")
		)
		(fp_line
			(start -0.7874 0.4064)
			(end 0.7874 0.4064)
			(stroke
				(width 0.1524)
				(type default)
			)
			(layer "B.SilkS")
		)
		(fp_line
			(start 0.67945 -0.305054)
			(end 0.12065 -0.305054)
			(stroke
				(width 0.1)
				(type default)
			)
			(layer "B.Fab")
		)
		(fp_line
			(start 0.12065 -0.305054)
			(end 0.12065 -0.2794)
			(stroke
				(width 0.1)
				(type default)
			)
			(layer "B.Fab")
		)
		(fp_line
			(start -0.12065 -0.3048)
			(end -0.67945 -0.3048)
			(stroke
				(width 0.1)
				(type default)
			)
			(layer "B.Fab")
		)
		(fp_line
			(start -0.67945 -0.3048)
			(end -0.67945 0.3048)
			(stroke
				(width 0.1)
				(type default)
			)
			(layer "B.Fab")
		)
		(fp_line
			(start 0.12065 -0.2794)
			(end -0.12065 -0.2794)
			(stroke
				(width 0.1)
				(type default)
			)
			(layer "B.Fab")
		)
		(fp_line
			(start -0.12065 -0.2794)
			(end -0.12065 -0.3048)
			(stroke
				(width 0.1)
				(type default)
			)
			(layer "B.Fab")
		)
		(fp_line
			(start 0.12065 0.2794)
			(end 0.12065 0.3048)
			(stroke
				(width 0.1)
				(type default)
			)
			(layer "B.Fab")
		)
		(fp_line
			(start -0.120396 0.2794)
			(end 0.12065 0.2794)
			(stroke
				(width 0.1)
				(type default)
			)
			(layer "B.Fab")
		)
		(fp_line
			(start 0.67945 0.3048)
			(end 0.67945 -0.305054)
			(stroke
				(width 0.1)
				(type default)
			)
			(layer "B.Fab")
		)
		(fp_line
			(start 0.12065 0.3048)
			(end 0.67945 0.3048)
			(stroke
				(width 0.1)
				(type default)
			)
			(layer "B.Fab")
		)
		(fp_line
			(start -0.120396 0.3048)
			(end -0.120396 0.2794)
			(stroke
				(width 0.1)
				(type default)
			)
			(layer "B.Fab")
		)
		(fp_line
			(start -0.67945 0.3048)
			(end -0.120396 0.3048)
			(stroke
				(width 0.1)
				(type default)
			)
			(layer "B.Fab")
		)
		(pad "1" smd circle
			(at 0.40005 0 270)
			(size 0 0)
			(layers "B.Cu" "B.Mask" "B.Paste")
			(net "SPI_PEX0_CLK_MUX")
		)
		(pad "2" smd circle
			(at -0.40005 0 270)
			(size 0 0)
			(layers "B.Cu" "B.Mask" "B.Paste")
			(net "SPI_PEX0_CLK_MUX_R")
		)
	)
	(footprint ""
		(layer "B.Cu")
		(at 224.354644 -231.225598 -90)
		(property "Reference" "R1479"
			(at 0 0 90)
			(layer "B.SilkS")
			(hide yes)
			(effects
				(font
					(size 1.27 1.27)
				)
				(justify mirror)
			)
		)
		(property "Value" ""
			(at 0 0 90)
			(layer "B.Fab")
			(effects
				(font
					(size 1.27 1.27)
				)
				(justify mirror)
			)
		)
		(duplicate_pad_numbers_are_jumpers no)
		(fp_line
			(start -0.7874 0.4064)
			(end 0.7874 0.4064)
			(stroke
				(width 0.1524)
				(type default)
			)
			(layer "B.SilkS")
		)
		(fp_line
			(start 0.7874 0.4064)
			(end 0.7874 -0.4064)
			(stroke
				(width 0.1524)
				(type default)
			)
			(layer "B.SilkS")
		)
		(fp_line
			(start -0.7874 -0.4064)
			(end -0.7874 0.4064)
			(stroke
				(width 0.1524)
				(type default)
			)
			(layer "B.SilkS")
		)
		(fp_line
			(start 0.7874 -0.4064)
			(end -0.7874 -0.4064)
			(stroke
				(width 0.1524)
				(type default)
			)
			(layer "B.SilkS")
		)
		(fp_line
			(start -0.67945 0.3048)
			(end -0.120396 0.3048)
			(stroke
				(width 0.1)
				(type default)
			)
			(layer "B.Fab")
		)
		(fp_line
			(start -0.120396 0.3048)
			(end -0.120396 0.2794)
			(stroke
				(width 0.1)
				(type default)
			)
			(layer "B.Fab")
		)
		(fp_line
			(start 0.12065 0.3048)
			(end 0.67945 0.3048)
			(stroke
				(width 0.1)
				(type default)
			)
			(layer "B.Fab")
		)
		(fp_line
			(start 0.67945 0.3048)
			(end 0.67945 -0.305054)
			(stroke
				(width 0.1)
				(type default)
			)
			(layer "B.Fab")
		)
		(fp_line
			(start -0.120396 0.2794)
			(end 0.12065 0.2794)
			(stroke
				(width 0.1)
				(type default)
			)
			(layer "B.Fab")
		)
		(fp_line
			(start 0.12065 0.2794)
			(end 0.12065 0.3048)
			(stroke
				(width 0.1)
				(type default)
			)
			(layer "B.Fab")
		)
		(fp_line
			(start -0.12065 -0.2794)
			(end -0.12065 -0.3048)
			(stroke
				(width 0.1)
				(type default)
			)
			(layer "B.Fab")
		)
		(fp_line
			(start 0.12065 -0.2794)
			(end -0.12065 -0.2794)
			(stroke
				(width 0.1)
				(type default)
			)
			(layer "B.Fab")
		)
		(fp_line
			(start -0.67945 -0.3048)
			(end -0.67945 0.3048)
			(stroke
				(width 0.1)
				(type default)
			)
			(layer "B.Fab")
		)
		(fp_line
			(start -0.12065 -0.3048)
			(end -0.67945 -0.3048)
			(stroke
				(width 0.1)
				(type default)
			)
			(layer "B.Fab")
		)
		(fp_line
			(start 0.12065 -0.305054)
			(end 0.12065 -0.2794)
			(stroke
				(width 0.1)
				(type default)
			)
			(layer "B.Fab")
		)
		(fp_line
			(start 0.67945 -0.305054)
			(end 0.12065 -0.305054)
			(stroke
				(width 0.1)
				(type default)
			)
			(layer "B.Fab")
		)
		(pad "1" smd circle
			(at 0.40005 0 90)
			(size 0 0)
			(layers "B.Cu" "B.Mask" "B.Paste")
			(net "SMB_NIC1_SCL")
		)
		(pad "2" smd circle
			(at -0.40005 0 90)
			(size 0 0)
			(layers "B.Cu" "B.Mask" "B.Paste")
			(net "SMB_NIC1_R_SCL")
		)
	)
	(footprint ""
		(layer "B.Cu")
		(at 13.472668 -281.9654 180)
		(property "Reference" "PC213"
			(at 0 0 0)
			(layer "B.SilkS")
			(hide yes)
			(effects
				(font
					(size 1.27 1.27)
				)
				(justify mirror)
			)
		)
		(property "Value" ""
			(at 0 0 0)
			(layer "B.Fab")
			(effects
				(font
					(size 1.27 1.27)
				)
				(justify mirror)
			)
		)
		(duplicate_pad_numbers_are_jumpers no)
		(fp_line
			(start 1.524 0.762)
			(end 1.524 -0.762)
			(stroke
				(width 0.1524)
				(type default)
			)
			(layer "B.SilkS")
		)
		(fp_line
			(start 1.524 -0.762)
			(end -1.524 -0.762)
			(stroke
				(width 0.1524)
				(type default)
			)
			(layer "B.SilkS")
		)
		(fp_line
			(start -1.524 0.762)
			(end 1.524 0.762)
			(stroke
				(width 0.1524)
				(type default)
			)
			(layer "B.SilkS")
		)
		(fp_line
			(start -1.524 -0.762)
			(end -1.524 0.762)
			(stroke
				(width 0.1524)
				(type default)
			)
			(layer "B.SilkS")
		)
		(fp_line
			(start 1.1049 0.724916)
			(end -1.1049 0.724916)
			(stroke
				(width 0.1)
				(type default)
			)
			(layer "B.Fab")
		)
		(fp_line
			(start 1.1049 -0.724916)
			(end 1.1049 0.724916)
			(stroke
				(width 0.1)
				(type default)
			)
			(layer "B.Fab")
		)
		(fp_line
			(start -1.1049 0.724916)
			(end -1.1049 -0.724916)
			(stroke
				(width 0.1)
				(type default)
			)
			(layer "B.Fab")
		)
		(fp_line
			(start -1.1049 -0.724916)
			(end 1.1049 -0.724916)
			(stroke
				(width 0.1)
				(type default)
			)
			(layer "B.Fab")
		)
		(pad "1" smd rect
			(at 0.889 0 180)
			(size 1.016 1.27)
			(layers "B.Cu" "B.Mask" "B.Paste")
			(net "P1V25_PEX0_R")
		)
		(pad "2" smd rect
			(at -0.889 0 180)
			(size 1.016 1.27)
			(layers "B.Cu" "B.Mask" "B.Paste")
			(net "GND")
		)
	)
	(footprint ""
		(layer "B.Cu")
		(at 174.277274 -286.399732 90)
		(property "Reference" "C3135"
			(at 0 0 90)
			(layer "B.SilkS")
			(hide yes)
			(effects
				(font
					(size 1.27 1.27)
				)
				(justify mirror)
			)
		)
		(property "Value" ""
			(at 0 0 90)
			(layer "B.Fab")
			(effects
				(font
					(size 1.27 1.27)
				)
				(justify mirror)
			)
		)
		(duplicate_pad_numbers_are_jumpers no)
		(fp_line
			(start 0.299974 -0.150114)
			(end -0.299974 -0.150114)
			(stroke
				(width 0.1)
				(type default)
			)
			(layer "B.Fab")
		)
		(fp_line
			(start -0.299974 -0.150114)
			(end -0.299974 0.150114)
			(stroke
				(width 0.1)
				(type default)
			)
			(layer "B.Fab")
		)
		(fp_line
			(start 0.299974 0.150114)
			(end 0.299974 -0.150114)
			(stroke
				(width 0.1)
				(type default)
			)
			(layer "B.Fab")
		)
		(fp_line
			(start -0.299974 0.150114)
			(end 0.299974 0.150114)
			(stroke
				(width 0.1)
				(type default)
			)
			(layer "B.Fab")
		)
		(pad "1" smd rect
			(at 0.2667 0 270)
			(size 0.3048 0.381)
			(layers "B.Cu" "B.Mask" "B.Paste")
			(net "P1V25_SERDES_VDDPLL_PEX1")
		)
		(pad "2" smd rect
			(at -0.2667 0 270)
			(size 0.3048 0.381)
			(layers "B.Cu" "B.Mask" "B.Paste")
			(net "GND")
		)
	)
	(footprint ""
		(layer "B.Cu")
		(at 336.662776 -326.945498 -90)
		(property "Reference" "C4326"
			(at 0 0 90)
			(layer "B.SilkS")
			(hide yes)
			(effects
				(font
					(size 1.27 1.27)
				)
				(justify mirror)
			)
		)
		(property "Value" ""
			(at 0 0 90)
			(layer "B.Fab")
			(effects
				(font
					(size 1.27 1.27)
				)
				(justify mirror)
			)
		)
		(duplicate_pad_numbers_are_jumpers no)
		(fp_line
			(start -1.2954 0.5842)
			(end 1.2954 0.5842)
			(stroke
				(width 0.1524)
				(type default)
			)
			(layer "B.SilkS")
		)
		(fp_line
			(start 1.2954 0.5842)
			(end 1.2954 -0.5842)
			(stroke
				(width 0.1524)
				(type default)
			)
			(layer "B.SilkS")
		)
		(fp_line
			(start -1.2954 -0.5842)
			(end -1.2954 0.5842)
			(stroke
				(width 0.1524)
				(type default)
			)
			(layer "B.SilkS")
		)
		(fp_line
			(start 1.2954 -0.5842)
			(end -1.2954 -0.5842)
			(stroke
				(width 0.1524)
				(type default)
			)
			(layer "B.SilkS")
		)
		(fp_line
			(start -0.8636 0.4572)
			(end 0.8636 0.4572)
			(stroke
				(width 0.1)
				(type default)
			)
			(layer "B.Fab")
		)
		(fp_line
			(start 0.8636 0.4572)
			(end 0.8636 0.4064)
			(stroke
				(width 0.1)
				(type default)
			)
			(layer "B.Fab")
		)
		(fp_line
			(start -1.1938 0.4064)
			(end -0.8636 0.4064)
			(stroke
				(width 0.1)
				(type default)
			)
			(layer "B.Fab")
		)
		(fp_line
			(start -0.8636 0.4064)
			(end -0.8636 0.4572)
			(stroke
				(width 0.1)
				(type default)
			)
			(layer "B.Fab")
		)
		(fp_line
			(start 0.8636 0.4064)
			(end 1.1938 0.4064)
			(stroke
				(width 0.1)
				(type default)
			)
			(layer "B.Fab")
		)
		(fp_line
			(start 1.1938 0.4064)
			(end 1.1938 -0.4064)
			(stroke
				(width 0.1)
				(type default)
			)
			(layer "B.Fab")
		)
		(fp_line
			(start -1.1938 -0.4064)
			(end -1.1938 0.4064)
			(stroke
				(width 0.1)
				(type default)
			)
			(layer "B.Fab")
		)
		(fp_line
			(start -0.8636 -0.4064)
			(end -1.1938 -0.4064)
			(stroke
				(width 0.1)
				(type default)
			)
			(layer "B.Fab")
		)
		(fp_line
			(start 0.8636 -0.4064)
			(end 0.8636 -0.4572)
			(stroke
				(width 0.1)
				(type default)
			)
			(layer "B.Fab")
		)
		(fp_line
			(start 1.1938 -0.4064)
			(end 0.8636 -0.4064)
			(stroke
				(width 0.1)
				(type default)
			)
			(layer "B.Fab")
		)
		(fp_line
			(start -0.8636 -0.4572)
			(end -0.8636 -0.4064)
			(stroke
				(width 0.1)
				(type default)
			)
			(layer "B.Fab")
		)
		(fp_line
			(start 0.8636 -0.4572)
			(end -0.8636 -0.4572)
			(stroke
				(width 0.1)
				(type default)
			)
			(layer "B.Fab")
		)
		(pad "1" smd rect
			(at 0.7366 0 180)
			(size 0.7112 0.8128)
			(layers "B.Cu" "B.Mask" "B.Paste")
			(net "P0V8_SERDES_VDDA_PEX2_C8")
		)
		(pad "2" smd rect
			(at -0.7366 0 180)
			(size 0.7112 0.8128)
			(layers "B.Cu" "B.Mask" "B.Paste")
			(net "GND")
		)
	)
	(footprint ""
		(layer "B.Cu")
		(at 396.3416 -303.024794)
		(property "Reference" "C3517"
			(at 0 0 0)
			(layer "B.SilkS")
			(hide yes)
			(effects
				(font
					(size 1.27 1.27)
				)
				(justify mirror)
			)
		)
		(property "Value" ""
			(at 0 0 0)
			(layer "B.Fab")
			(effects
				(font
					(size 1.27 1.27)
				)
				(justify mirror)
			)
		)
		(duplicate_pad_numbers_are_jumpers no)
		(fp_line
			(start -0.299974 -0.150114)
			(end -0.299974 0.150114)
			(stroke
				(width 0.1)
				(type default)
			)
			(layer "B.Fab")
		)
		(fp_line
			(start -0.299974 0.150114)
			(end 0.299974 0.150114)
			(stroke
				(width 0.1)
				(type default)
			)
			(layer "B.Fab")
		)
		(fp_line
			(start 0.299974 -0.150114)
			(end -0.299974 -0.150114)
			(stroke
				(width 0.1)
				(type default)
			)
			(layer "B.Fab")
		)
		(fp_line
			(start 0.299974 0.150114)
			(end 0.299974 -0.150114)
			(stroke
				(width 0.1)
				(type default)
			)
			(layer "B.Fab")
		)
		(pad "1" smd rect
			(at 0.2667 0 180)
			(size 0.3048 0.381)
			(layers "B.Cu" "B.Mask" "B.Paste")
			(net "P1V8_VDDA_PEX3")
		)
		(pad "2" smd rect
			(at -0.2667 0 180)
			(size 0.3048 0.381)
			(layers "B.Cu" "B.Mask" "B.Paste")
			(net "GND")
		)
	)
	(footprint ""
		(layer "B.Cu")
		(at 165.655244 -157.0736 180)
		(property "Reference" "R103"
			(at 0 0 0)
			(layer "B.SilkS")
			(hide yes)
			(effects
				(font
					(size 1.27 1.27)
				)
				(justify mirror)
			)
		)
		(property "Value" ""
			(at 0 0 0)
			(layer "B.Fab")
			(effects
				(font
					(size 1.27 1.27)
				)
				(justify mirror)
			)
		)
		(duplicate_pad_numbers_are_jumpers no)
		(fp_line
			(start 0.7874 0.4064)
			(end 0.7874 -0.4064)
			(stroke
				(width 0.1524)
				(type default)
			)
			(layer "B.SilkS")
		)
		(fp_line
			(start 0.7874 -0.4064)
			(end -0.7874 -0.4064)
			(stroke
				(width 0.1524)
				(type default)
			)
			(layer "B.SilkS")
		)
		(fp_line
			(start -0.7874 0.4064)
			(end 0.7874 0.4064)
			(stroke
				(width 0.1524)
				(type default)
			)
			(layer "B.SilkS")
		)
		(fp_line
			(start -0.7874 -0.4064)
			(end -0.7874 0.4064)
			(stroke
				(width 0.1524)
				(type default)
			)
			(layer "B.SilkS")
		)
		(fp_line
			(start 0.67945 0.3048)
			(end 0.67945 -0.305054)
			(stroke
				(width 0.1)
				(type default)
			)
			(layer "B.Fab")
		)
		(fp_line
			(start 0.67945 -0.305054)
			(end 0.12065 -0.305054)
			(stroke
				(width 0.1)
				(type default)
			)
			(layer "B.Fab")
		)
		(fp_line
			(start 0.12065 0.3048)
			(end 0.67945 0.3048)
			(stroke
				(width 0.1)
				(type default)
			)
			(layer "B.Fab")
		)
		(fp_line
			(start 0.12065 0.2794)
			(end 0.12065 0.3048)
			(stroke
				(width 0.1)
				(type default)
			)
			(layer "B.Fab")
		)
		(fp_line
			(start 0.12065 -0.2794)
			(end -0.12065 -0.2794)
			(stroke
				(width 0.1)
				(type default)
			)
			(layer "B.Fab")
		)
		(fp_line
			(start 0.12065 -0.305054)
			(end 0.12065 -0.2794)
			(stroke
				(width 0.1)
				(type default)
			)
			(layer "B.Fab")
		)
		(fp_line
			(start -0.120396 0.3048)
			(end -0.120396 0.2794)
			(stroke
				(width 0.1)
				(type default)
			)
			(layer "B.Fab")
		)
		(fp_line
			(start -0.120396 0.2794)
			(end 0.12065 0.2794)
			(stroke
				(width 0.1)
				(type default)
			)
			(layer "B.Fab")
		)
		(fp_line
			(start -0.12065 -0.2794)
			(end -0.12065 -0.3048)
			(stroke
				(width 0.1)
				(type default)
			)
			(layer "B.Fab")
		)
		(fp_line
			(start -0.12065 -0.3048)
			(end -0.67945 -0.3048)
			(stroke
				(width 0.1)
				(type default)
			)
			(layer "B.Fab")
		)
		(fp_line
			(start -0.67945 0.3048)
			(end -0.120396 0.3048)
			(stroke
				(width 0.1)
				(type default)
			)
			(layer "B.Fab")
		)
		(fp_line
			(start -0.67945 -0.3048)
			(end -0.67945 0.3048)
			(stroke
				(width 0.1)
				(type default)
			)
			(layer "B.Fab")
		)
		(pad "1" smd circle
			(at 0.40005 0)
			(size 0 0)
			(layers "B.Cu" "B.Mask" "B.Paste")
			(net "NIC2_RBT_ARB_OUT")
		)
		(pad "2" smd circle
			(at -0.40005 0)
			(size 0 0)
			(layers "B.Cu" "B.Mask" "B.Paste")
			(net "NIC2_RBT_ARB_IN")
		)
	)
	(footprint ""
		(layer "B.Cu")
		(at 305.6001 -110.115096)
		(property "Reference" "C925"
			(at 0 0 0)
			(layer "B.SilkS")
			(hide yes)
			(effects
				(font
					(size 1.27 1.27)
				)
				(justify mirror)
			)
		)
		(property "Value" ""
			(at 0 0 0)
			(layer "B.Fab")
			(effects
				(font
					(size 1.27 1.27)
				)
				(justify mirror)
			)
		)
		(duplicate_pad_numbers_are_jumpers no)
		(fp_line
			(start -0.299974 -0.150114)
			(end -0.299974 0.150114)
			(stroke
				(width 0.1)
				(type default)
			)
			(layer "B.Fab")
		)
		(fp_line
			(start -0.299974 0.150114)
			(end 0.299974 0.150114)
			(stroke
				(width 0.1)
				(type default)
			)
			(layer "B.Fab")
		)
		(fp_line
			(start 0.299974 -0.150114)
			(end -0.299974 -0.150114)
			(stroke
				(width 0.1)
				(type default)
			)
			(layer "B.Fab")
		)
		(fp_line
			(start 0.299974 0.150114)
			(end 0.299974 -0.150114)
			(stroke
				(width 0.1)
				(type default)
			)
			(layer "B.Fab")
		)
		(pad "1" smd rect
			(at 0.2667 0 180)
			(size 0.3048 0.381)
			(layers "B.Cu" "B.Mask" "B.Paste")
			(net "P12V_NIC5")
		)
		(pad "2" smd rect
			(at -0.2667 0 180)
			(size 0.3048 0.381)
			(layers "B.Cu" "B.Mask" "B.Paste")
			(net "GND")
		)
	)
)
